# SCM (Grand Teton) — schematic netlist excerpt (pin names and nets, part order shuffled) for the footprints in the layout excerpt that follows; sources: Cadence DE-HDL packaged netlist, KiCad conversion of 12092022_DA0F0TMDCD0_F0T_Management_Board_D_brd_V3_OCP.brd

R423  Q_RES  33.2 1% CHIP  pkg 0402LF  page 12 : A = SMB_BMC_MM13_R_SCL ; B = SMB_BMC_MM13_SCL
R853  Q_RES  0 5% CHIP  pkg 0402LF  page 15 : A = FM_INTRUDER_R_N ; B = FM_INTRUDER_N

(kicad_pcb
	(version 20260206)
	(generator "pcbnew")
	(generator_version "10.0")
	(general
		(thickness 1.6)
		(legacy_teardrops no)
	)
	(paper "A4")
	(title_block
		(title "12092022_DA0F0TMDCD0_F0T_Management_Board_D_brd_V3_OCP.brd")
		(comment 1 "Grand Teton / footprints 135-136 of 1440")
	)
	(layers
		(0 "F.Cu" signal "TOP")
		(4 "In1.Cu" signal "GND")
		(6 "In2.Cu" signal "IN1")
		(8 "In3.Cu" signal "GND1")
		(10 "In4.Cu" signal "IN2")
		(12 "In5.Cu" signal "VCC")
		(14 "In6.Cu" signal "VCC1")
		(16 "In7.Cu" signal "IN3")
		(18 "In8.Cu" signal "GND2")
		(20 "In9.Cu" signal "IN4")
		(22 "In10.Cu" signal "GND3")
		(2 "B.Cu" signal "BOTTOM")
		(9 "F.Adhes" user "F.Adhesive")
		(11 "B.Adhes" user "B.Adhesive")
		(13 "F.Paste" user "Package Geometry/Pastemask Top")
		(15 "B.Paste" user "Package Geometry/Pastemask Bottom")
		(5 "F.SilkS" user "Ref Des/Silkscreen Top")
		(7 "B.SilkS" user "Ref Des/Silkscreen Bottom")
		(1 "F.Mask" user "Board Geometry/Soldermask Top")
		(3 "B.Mask" user "Board Geometry/Soldermask Bottom")
		(17 "Dwgs.User" user "User.Drawings")
		(19 "Cmts.User" user "User.Comments")
		(21 "Eco1.User" user "User.Eco1")
		(23 "Eco2.User" user "User.Eco2")
		(25 "Edge.Cuts" user "Board Geometry/Outline")
		(27 "Margin" user)
		(31 "F.CrtYd" user "Package Geometry/Place Bound Top")
		(29 "B.CrtYd" user "Package Geometry/Place Bound Bottom")
		(35 "F.Fab" user "Ref Des/Assembly Top")
		(33 "B.Fab" user "Ref Des/Assembly Bottom")
	)
	(footprint ""
		(layer "F.Cu")
		(at 38.123876 -46.378876 180)
		(property "Reference" "R423"
			(at 0 0 180)
			(layer "F.SilkS")
			(hide yes)
			(effects
				(font
					(size 1.27 1.27)
				)
			)
		)
		(property "Value" ""
			(at 0 0 180)
			(layer "F.Fab")
			(effects
				(font
					(size 1.27 1.27)
				)
			)
		)
		(duplicate_pad_numbers_are_jumpers no)
		(fp_line
			(start 0.7874 0.4064)
			(end -0.7874 0.4064)
			(stroke
				(width 0.1524)
				(type default)
			)
			(layer "F.SilkS")
		)
		(fp_line
			(start 0.7874 -0.4064)
			(end 0.7874 0.4064)
			(stroke
				(width 0.1524)
				(type default)
			)
			(layer "F.SilkS")
		)
		(fp_line
			(start -0.7874 0.4064)
			(end -0.7874 -0.4064)
			(stroke
				(width 0.1524)
				(type default)
			)
			(layer "F.SilkS")
		)
		(fp_line
			(start -0.7874 -0.4064)
			(end 0.7874 -0.4064)
			(stroke
				(width 0.1524)
				(type default)
			)
			(layer "F.SilkS")
		)
		(fp_line
			(start 0.67945 0.3048)
			(end 0.120396 0.3048)
			(stroke
				(width 0.1)
				(type default)
			)
			(layer "F.Fab")
		)
		(fp_line
			(start 0.67945 -0.3048)
			(end 0.67945 0.3048)
			(stroke
				(width 0.1)
				(type default)
			)
			(layer "F.Fab")
		)
		(fp_line
			(start 0.12065 -0.2794)
			(end 0.12065 -0.3048)
			(stroke
				(width 0.1)
				(type default)
			)
			(layer "F.Fab")
		)
		(fp_line
			(start 0.12065 -0.3048)
			(end 0.67945 -0.3048)
			(stroke
				(width 0.1)
				(type default)
			)
			(layer "F.Fab")
		)
		(fp_line
			(start 0.120396 0.3048)
			(end 0.120396 0.2794)
			(stroke
				(width 0.1)
				(type default)
			)
			(layer "F.Fab")
		)
		(fp_line
			(start 0.120396 0.2794)
			(end -0.12065 0.2794)
			(stroke
				(width 0.1)
				(type default)
			)
			(layer "F.Fab")
		)
		(fp_line
			(start -0.12065 0.3048)
			(end -0.67945 0.3048)
			(stroke
				(width 0.1)
				(type default)
			)
			(layer "F.Fab")
		)
		(fp_line
			(start -0.12065 0.2794)
			(end -0.12065 0.3048)
			(stroke
				(width 0.1)
				(type default)
			)
			(layer "F.Fab")
		)
		(fp_line
			(start -0.12065 -0.2794)
			(end 0.12065 -0.2794)
			(stroke
				(width 0.1)
				(type default)
			)
			(layer "F.Fab")
		)
		(fp_line
			(start -0.12065 -0.305054)
			(end -0.12065 -0.2794)
			(stroke
				(width 0.1)
				(type default)
			)
			(layer "F.Fab")
		)
		(fp_line
			(start -0.67945 0.3048)
			(end -0.67945 -0.305054)
			(stroke
				(width 0.1)
				(type default)
			)
			(layer "F.Fab")
		)
		(fp_line
			(start -0.67945 -0.305054)
			(end -0.12065 -0.305054)
			(stroke
				(width 0.1)
				(type default)
			)
			(layer "F.Fab")
		)
		(pad "1" smd circle
			(at -0.40005 0 180)
			(size 0 0)
			(layers "F.Cu" "F.Mask" "F.Paste")
			(net "SMB_BMC_MM13_R_SCL")
		)
		(pad "2" smd circle
			(at 0.40005 0 180)
			(size 0 0)
			(layers "F.Cu" "F.Mask" "F.Paste")
			(net "SMB_BMC_MM13_SCL")
		)
	)
	(footprint ""
		(layer "F.Cu")
		(at 40.767 -51.8414 90)
		(property "Reference" "R853"
			(at 0 0 90)
			(layer "F.SilkS")
			(hide yes)
			(effects
				(font
					(size 1.27 1.27)
				)
			)
		)
		(property "Value" ""
			(at 0 0 90)
			(layer "F.Fab")
			(effects
				(font
					(size 1.27 1.27)
				)
			)
		)
		(duplicate_pad_numbers_are_jumpers no)
		(fp_line
			(start 0.7874 -0.4064)
			(end 0.7874 0.4064)
			(stroke
				(width 0.1524)
				(type default)
			)
			(layer "F.SilkS")
		)
		(fp_line
			(start -0.7874 -0.4064)
			(end 0.7874 -0.4064)
			(stroke
				(width 0.1524)
				(type default)
			)
			(layer "F.SilkS")
		)
		(fp_line
			(start 0.7874 0.4064)
			(end -0.7874 0.4064)
			(stroke
				(width 0.1524)
				(type default)
			)
			(layer "F.SilkS")
		)
		(fp_line
			(start -0.7874 0.4064)
			(end -0.7874 -0.4064)
			(stroke
				(width 0.1524)
				(type default)
			)
			(layer "F.SilkS")
		)
		(fp_line
			(start -0.12065 -0.305054)
			(end -0.12065 -0.2794)
			(stroke
				(width 0.1)
				(type default)
			)
			(layer "F.Fab")
		)
		(fp_line
			(start -0.67945 -0.305054)
			(end -0.12065 -0.305054)
			(stroke
				(width 0.1)
				(type default)
			)
			(layer "F.Fab")
		)
		(fp_line
			(start 0.67945 -0.3048)
			(end 0.67945 0.3048)
			(stroke
				(width 0.1)
				(type default)
			)
			(layer "F.Fab")
		)
		(fp_line
			(start 0.12065 -0.3048)
			(end 0.67945 -0.3048)
			(stroke
				(width 0.1)
				(type default)
			)
			(layer "F.Fab")
		)
		(fp_line
			(start 0.12065 -0.2794)
			(end 0.12065 -0.3048)
			(stroke
				(width 0.1)
				(type default)
			)
			(layer "F.Fab")
		)
		(fp_line
			(start -0.12065 -0.2794)
			(end 0.12065 -0.2794)
			(stroke
				(width 0.1)
				(type default)
			)
			(layer "F.Fab")
		)
		(fp_line
			(start 0.120396 0.2794)
			(end -0.12065 0.2794)
			(stroke
				(width 0.1)
				(type default)
			)
			(layer "F.Fab")
		)
		(fp_line
			(start -0.12065 0.2794)
			(end -0.12065 0.3048)
			(stroke
				(width 0.1)
				(type default)
			)
			(layer "F.Fab")
		)
		(fp_line
			(start 0.67945 0.3048)
			(end 0.120396 0.3048)
			(stroke
				(width 0.1)
				(type default)
			)
			(layer "F.Fab")
		)
		(fp_line
			(start 0.120396 0.3048)
			(end 0.120396 0.2794)
			(stroke
				(width 0.1)
				(type default)
			)
			(layer "F.Fab")
		)
		(fp_line
			(start -0.12065 0.3048)
			(end -0.67945 0.3048)
			(stroke
				(width 0.1)
				(type default)
			)
			(layer "F.Fab")
		)
		(fp_line
			(start -0.67945 0.3048)
			(end -0.67945 -0.305054)
			(stroke
				(width 0.1)
				(type default)
			)
			(layer "F.Fab")
		)
		(pad "1" smd circle
			(at -0.40005 0 90)
			(size 0 0)
			(layers "F.Cu" "F.Mask" "F.Paste")
			(net "FM_INTRUDER_R_N")
		)
		(pad "2" smd circle
			(at 0.40005 0 90)
			(size 0 0)
			(layers "F.Cu" "F.Mask" "F.Paste")
			(net "FM_INTRUDER_N")
		)
	)
)
